#ISCELL
  pure_quanta quanta_title_block_c *
  *
#CELL
  pure_quanta pt5161lrs *
  page460_i1
#ISCELL
  standard tap *
  page460_i10
#ISCELL
  standard tap *
  page460_i11
#ISCELL
  standard tap *
  page460_i12
#ISCELL
  standard tap *
  page460_i13
#ISCELL
  standard tap *
  page460_i14
#ISCELL
  standard tap *
  page460_i15
#ISCELL
  standard tap *
  page460_i16
#ISCELL
  standard tap *
  page460_i17
#ISCELL
  standard offpage *
  page460_i18
#ISCELL
  standard offpage *
  page460_i19
#ISCELL
  standard tap *
  page460_i2
#ISCELL
  standard tap *
  page460_i20
#ISCELL
  standard tap *
  page460_i21
#ISCELL
  standard tap *
  page460_i22
#ISCELL
  standard tap *
  page460_i23
#ISCELL
  standard tap *
  page460_i24
#ISCELL
  standard tap *
  page460_i25
#ISCELL
  standard tap *
  page460_i26
#ISCELL
  standard tap *
  page460_i27
#ISCELL
  standard tap *
  page460_i28
#ISCELL
  standard tap *
  page460_i29
#ISCELL
  standard tap *
  page460_i3
#ISCELL
  standard tap *
  page460_i30
#ISCELL
  standard tap *
  page460_i31
#ISCELL
  standard tap *
  page460_i32
#ISCELL
  standard tap *
  page460_i33
#ISCELL
  standard tap *
  page460_i34
#ISCELL
  standard tap *
  page460_i35
#ISCELL
  standard offpage *
  page460_i36
#ISCELL
  standard offpage *
  page460_i37
#CELL
  pure_quanta pt5161lrs *
  page460_i38
#ISCELL
  standard tap *
  page460_i4
#ISCELL
  standard tap *
  page460_i5
#ISCELL
  standard tap *
  page460_i6
#ISCELL
  standard tap *
  page460_i7
#ISCELL
  standard tap *
  page460_i8
#ISCELL
  standard tap *
  page460_i9
